FILE_TYPE = CONNECTIVITY;
{Allegro Design Entry HDL 16.6-p007 (v16-6-112F) 10/10/2012}
"PAGE_NUMBER" = 238;
0"NC";
1"GND\g";
2"GND\g";
3"GND\g";
4"P3V3_STBY\g";
5"GND\g";
6"GND\g";
7"GND\g";
8"P3V3_STBY\g";
9"P1V15_AUX_BMC\g"VOLTAGE"1.5";
10"P3V3_STBY\g"VOLTAGE"3.3 V";
11"GND\g";
12"PWRGD_P1V538_BMC_STBY";
13"PWRGD_P1V26_BMC_STBY";
14"PWRGD_P1V26_BMC_STBY_R";
15"VR_P1V26_BMC_STBY_FB";
%"GND"
"1","(1025,1850)","0","mstr_symbols","I13";
;
BOM_COST"P1V26_BMC_STBY_VR"
SIZE"1B"
CDS_LIB"mstr_symbols"
VOLTAGE"0.0V"
ROOM"P1V26_BMC_STBY_VR"
BODY_TYPE"PLUMBING"
HDL_POWER"GND"
P1V5_STBY_IBMC""
P1V5_STBY_IBMC_VR"";
"A\NAC"1;
%"RES"
"1","(1025,2100)","1","mstr_discrete","I14";
;
CDS_SEC"1"
SEC"1"
BOM_COST"P1V26_BMC_STBY_VR"
SEC_TYPE"0402"
CDS_LIB"mstr_discrete"
CDS_LOCATION"R9F8"
ROOM"P1V26_BMC_STBY_VR"
TOLERANCE"1%"
P1V5_STBY_IBMC""
P1V5_STBY_IBMC_VR""
LOCATION"R9F8"
PACK_TYPE"0402"
PART_NUMBER"G21796-016"
MATERIAL"CHIP"
WATTAGE"1/16W"
VALUE"10.0K";
"B"
$PN"2"15;
"A"
$PN"1"1;
%"GND"
"1","(400,2200)","0","mstr_symbols","I15";
;
BOM_COST"P1V26_BMC_STBY_VR"
VOLTAGE"0.0V"
CDS_LIB"mstr_symbols"
SIZE"1B"
ROOM"P1V26_BMC_STBY_VR"
BODY_TYPE"PLUMBING"
HDL_POWER"GND"
P1V5_STBY_IBMC""
P1V5_STBY_IBMC_VR"";
"A\NAC"2;
%"CAP"
"1","(1250,3050)","0","mstr_discrete","I19";
;
BOM_COST"P1V26_BMC_STBY_VR"
CDS_SEC"1"
$SEC"1"
CDS_LOCATION"C9F8"
ROOM"P1V26_BMC_STBY_VR"
VOLTAGE"50V"
CDS_LIB"mstr_discrete"
PACK_TYPE"0402LF"
LOCATION"C9F8"
VALUE"1000PF"
PART_NUMBER"A36096-046"
TOLERANCE"10%"
MATERIAL"X7R";
"A"
$PN"1"14;
"B"
$PN"2"3;
%"GND"
"1","(1250,2825)","0","mstr_symbols","I20";
;
SIZE"1B"
CDS_LIB"mstr_symbols"
VOLTAGE"0.0V"
BOM_COST"P1V26_BMC_STBY_VR"
ROOM"P1V26_BMC_STBY_VR"
BODY_TYPE"PLUMBING"
HDL_POWER"GND";
"A\NAC"3;
%"RES"
"2","(900,3500)","0","mstr_discrete","I21";
;
CDS_SEC"1"
CDS_LOCATION"R9F13"
SEC"1"
SEC_TYPE"0402"
BOM_COST"P1V26_BMC_STBY_VR"
ROOM"P1V26_BMC_STBY_VR"
CDS_LIB"mstr_discrete"
VALUE"10.0K"
LOCATION"R9F13"
PART_NUMBER"G21796-016"
PACK_TYPE"0402"
MATERIAL"CHIP"
WATTAGE"1/16W"
P1V5_STBY_IBMC""
P1V5_STBY_IBMC_VR""
TOLERANCE"1%";
"A"
$PN"1"4;
"B"
$PN"2"14;
%"P3V3_STBY"
"1","(900,3825)","0","mstr_symbols","I22";
;
SIZE"1B"
VOLTAGE"3.3V"
CDS_LIB"mstr_symbols"
BODY_TYPE"PLUMBING"
HDL_POWER"P3V3_STBY";
"G\NAC"4;
%"CAP"
"1","(1950,2525)","0","mstr_discrete","I23";
;
CDS_SEC"1"
SEC_TYPE"0603"
ROOM"P1V26_BMC_STBY_VR"
SEC"1"
BOM_COST"P1V26_BMC_STBY_VR"
CDS_LOCATION"C9E10"
CDS_LIB"mstr_discrete"
PACK_TYPE"0603"
MATERIAL"X6S"
VOLTAGE"6.3V"
TOLERANCE"20%"
VALUE"10UF"
LOCATION"C9E10"
PART_NUMBER"E15431-002";
"A"
$PN"1"9;
"B"
$PN"2"5;
%"GND"
"1","(2175,2075)","0","mstr_symbols","I27";
;
BOM_COST"P1V26_BMC_STBY_VR"
CDS_LIB"mstr_symbols"
SIZE"1B"
VOLTAGE"0.0V"
ROOM"P1V26_BMC_STBY_VR"
BODY_TYPE"PLUMBING"
HDL_POWER"GND"
P1V5_STBY_IBMC""
P1V5_STBY_IBMC_VR"";
"A\NAC"5;
%"GND"
"1","(-2000,1775)","0","mstr_symbols","I3";
;
BOM_COST"P1V26_BMC_STBY_VR"
CDS_LIB"mstr_symbols"
SIZE"1B"
VOLTAGE"0.0V"
ROOM"P1V26_BMC_STBY_VR"
BODY_TYPE"PLUMBING"
HDL_POWER"GND"
P1V5_STBY_IBMC_VR""
P1V5_STBY_IBMC"";
"A\NAC"6;
%"CAP"
"1","(2325,2525)","0","mstr_discrete","I30";
;
CDS_SEC"1"
ROOM"P1V26_BMC_STBY_VR"
CDS_LOCATION"C9F4"
SEC"1"
SEC_TYPE"0805LF"
BOM_COST"P1V26_BMC_STBY_VR"
CDS_LIB"mstr_discrete"
VALUE"22UF"
TOLERANCE"20%"
VOLTAGE"4V"
LOCATION"C9F4"
MATERIAL"X6S"
PART_NUMBER"C95333-002"
PACK_TYPE"0805LF";
"A"
$PN"1"9;
"B"
$PN"2"5;
%"CAP"
"1","(-1275,2150)","0","mstr_discrete","I39";
;
CDS_SEC"1"
SEC_TYPE"0402"
SEC"1"
CDS_LIB"mstr_discrete"
CDS_LOCATION"C9E11"
PART_NUMBER"D97712-011"
PACK_TYPE"0402"
TOLERANCE"10%"
VOLTAGE"16V"
MATERIAL"X6S"
LOCATION"C9E11"
VALUE"1.0UF";
"A"
$PN"1"8;
"B"
$PN"2"7;
%"GND"
"1","(-1275,1750)","0","mstr_symbols","I4";
;
VOLTAGE"0.0V"
CDS_LIB"mstr_symbols"
SIZE"1B"
BODY_TYPE"PLUMBING"
HDL_POWER"GND";
"A\NAC"7;
%"RT9059"
"1","(-175,2700)","0","mstr_vreg","I40";
;
CDS_SEC"1"
PACK_TYPE"DFN"
SEC_TYPE"DFN"
SEC"1"
CDS_LOCATION"EU9F1"
ROOM"P1V26_BMC_STBY_VR"
CDS_LIB"mstr_vreg"
PART_NUMBER"H65765-001"
MATERIAL"IC"
LOCATION"EU9F1";
"VIN<0>"
$PN"7"10;
"VIN<1>"
$PN"8"10;
"VIN<2>"
$PN"9"10;
"EN"
$PN"6"12;
"VOUT<0>"
$PN"1"9;
"VOUT<1>"
$PN"2"9;
"VOUT<2>"
$PN"3"9;
"GND"
$PN"11"2;
"ADJ_NC"
$PN"4"15;
"VDD"
$PN"10"8;
"PGOOD"
$PN"5"14;
%"RES"
"1","(1850,3200)","0","mstr_discrete","I41";
;
CDS_SEC"1"
ROOM"P1V26_BMC_STBY_VR"
SEC"1"
SEC_TYPE"0402"
CDS_LOCATION"R9F11"
CDS_LIB"mstr_discrete"
PACK_TYPE"0402"
PART_NUMBER"G21796-250"
LOCATION"R9F11"
TOLERANCE"1.0%"
VALUE"22.1"
MATERIAL"CHIP"
WATTAGE"1/16W";
"B"
$PN"2"13;
"A"
$PN"1"14;
%"P3V3_STBY"
"1","(-1275,3075)","0","mstr_symbols","I42";
;
SIZE"1B"
CDS_LIB"mstr_symbols"
VOLTAGE"3.3V"
BODY_TYPE"PLUMBING"
HDL_POWER"P3V3_STBY";
"G\NAC"8;
%"W_VCC_CIRCLE"
"1","(2325,2825)","0","w_power","I43";
;
CDS_LMAN_SYM_OUTLINE"-100,100,100,-100"
CDS_LIB"w_power"
BODY_TYPE"PLUMBING"
HDL_POWER"P1V15_AUX_BMC";
"VCC_CIRCLE \B"9;
%"P3V3_STBY"
"1","(-1875,3550)","0","mstr_symbols","I44";
;
CDS_LIB"mstr_symbols"
VOLTAGE"3.3V"
SIZE"1B"
BODY_TYPE"PLUMBING"
HDL_POWER"P3V3_STBY";
"G\NAC"10;
%"4K42R2F-GP"
"1","(1025,2475)","0","w_hdl","I45";
;
CDS_SEC"1"
$SEC"1"
CDS_LOCATION"R9F6"
PACK_TYPE"SMD-RG"
PART_NUMBER"64.44215.6DL"
CDS_LIB"w_hdl"
CDS_LMAN_SYM_OUTLINE"-50,75,50,-75"
VALUE"4K42R2F-GP"
LOCATION"R9F6";
"2"
$PN"2"15;
"1"
$PN"1"9;
%"CAP"
"1","(-2000,2175)","2","mstr_discrete","I5";
;
CDS_SEC"1"
$SEC"1"
CDS_LIB"mstr_discrete"
BOM_COST"P1V26_BMC_STBY_VR"
ROOM"P1V26_BMC_STBY_VR"
CDS_LOCATION"C9F9"
PART_NUMBER"A36096-046"
TOLERANCE"10%"
MATERIAL"EMPTY"
LOCATION"C9F9"
VALUE"1000PF"
PACK_TYPE"0402LF"
VOLTAGE"50V";
"A"
$PN"1"12;
"B"
$PN"2"6;
%"GND"
"1","(-1875,2775)","0","mstr_symbols","I6";
;
CDS_LIB"mstr_symbols"
SIZE"1B"
VOLTAGE"0.0V"
BODY_TYPE"PLUMBING"
HDL_POWER"GND";
"A\NAC"11;
%"CAP"
"1","(-1875,3025)","0","mstr_discrete","I7";
;
CDS_SEC"1"
SEC"1"
SEC_TYPE"0603"
ROOM"P1V26_BMC_STBY_VR"
CDS_LOCATION"C9F3"
BOM_COST"P1V26_BMC_STBY_VR"
CDS_LIB"mstr_discrete"
LOCATION"C9F3"
VALUE"10UF"
PART_NUMBER"E15431-002"
MATERIAL"X6S"
VOLTAGE"6.3V"
PACK_TYPE"0603"
TOLERANCE"20%";
"A"
$PN"1"10;
"B"
$PN"2"11;
END.
